# BASEBOARD_FAB2 (Tioga Pass) — schematic netlist excerpt (pin names and nets, part order shuffled) for the footprints in the layout excerpt that follows; sources: Cadence DE-HDL packaged netlist, KiCad conversion of Wiwynn_Tioga_Pass_MB.brd

R8D19  RES  49.9 1% CHIP  pkg 0402  page 178 : A = SGPIO_PCH_SATA_DOUT0 ; B = SGPIO_PCH_SATA_DOUT0_R
C3N23  CAP_A  1.0UF 6.3V 10% X6S  pkg 0402V  page 130 : A = P3V3_STBY ; B = GND
C8P33  CAP  100UF 4V 20% X5R  pkg 0805  page 225 : A = PVDDQ_GHJ ; B = GND

(kicad_pcb
	(version 20260206)
	(generator "pcbnew")
	(generator_version "10.0")
	(general
		(thickness 1.6)
		(legacy_teardrops no)
	)
	(paper "A4")
	(title_block
		(title "Wiwynn_Tioga_Pass_MB.brd")
		(comment 1 "Tioga Pass / footprints 3346-3348 of 4770")
	)
	(layers
		(0 "F.Cu" signal "TOP")
		(4 "In1.Cu" signal "L2GND")
		(6 "In2.Cu" signal "L3")
		(8 "In3.Cu" signal "L4GND")
		(10 "In4.Cu" signal "L5")
		(12 "In5.Cu" signal "L6GND")
		(14 "In6.Cu" signal "L7VCC")
		(16 "In7.Cu" signal "L8VCC")
		(18 "In8.Cu" signal "L9GND")
		(20 "In9.Cu" signal "L10")
		(22 "In10.Cu" signal "L11GND")
		(24 "In11.Cu" signal "L12")
		(26 "In12.Cu" signal "L13GND")
		(2 "B.Cu" signal "BOTTOM")
		(9 "F.Adhes" user "F.Adhesive")
		(11 "B.Adhes" user "B.Adhesive")
		(13 "F.Paste" user "Package Geometry/Pastemask Top")
		(15 "B.Paste" user "Package Geometry/Pastemask Bottom")
		(5 "F.SilkS" user "Ref Des/Silkscreen Top")
		(7 "B.SilkS" user "Ref Des/Silkscreen Bottom")
		(1 "F.Mask" user "Board Geometry/Soldermask Top")
		(3 "B.Mask" user "Board Geometry/Soldermask Bottom")
		(17 "Dwgs.User" user "User.Drawings")
		(19 "Cmts.User" user "User.Comments")
		(21 "Eco1.User" user "User.Eco1")
		(23 "Eco2.User" user "User.Eco2")
		(25 "Edge.Cuts" user "Board Geometry/Outline")
		(27 "Margin" user)
		(31 "F.CrtYd" user "Package Geometry/Place Bound Top")
		(29 "B.CrtYd" user "Package Geometry/Place Bound Bottom")
		(35 "F.Fab" user "Ref Des/Assembly Top")
		(33 "B.Fab" user "Ref Des/Assembly Bottom")
	)
	(footprint ""
		(layer "B.Cu")
		(at 391.668 -87.4395)
		(property "Reference" "R8D19"
			(at 0.8382 -0.67818 0)
			(unlocked yes)
			(layer "B.SilkS")
			(effects
				(font
					(size 0.4064 0.254)
					(thickness 0.1524)
				)
				(justify left mirror)
			)
		)
		(property "Value" ""
			(at 0 0 0)
			(layer "B.Fab")
			(effects
				(font
					(size 1.27 1.27)
				)
				(justify mirror)
			)
		)
		(duplicate_pad_numbers_are_jumpers no)
		(fp_poly
			(pts
				(xy 0.2794 -0.1016) (xy -0.2794 -0.1016) (xy -0.2794 0.9906) (xy 0.2794 0.9906)
			)
			(stroke
				(width 0)
				(type default)
			)
			(fill no)
			(layer "B.CrtYd")
		)
		(fp_line
			(start -0.2794 -0.1016)
			(end 0.2794 -0.1016)
			(stroke
				(width 0.1)
				(type default)
			)
			(layer "B.Fab")
		)
		(fp_line
			(start -0.2794 0.9906)
			(end -0.2794 -0.1016)
			(stroke
				(width 0.1)
				(type default)
			)
			(layer "B.Fab")
		)
		(fp_line
			(start 0.2794 -0.1016)
			(end 0.2794 0.9906)
			(stroke
				(width 0.1)
				(type default)
			)
			(layer "B.Fab")
		)
		(fp_line
			(start 0.2794 0.9906)
			(end -0.2794 0.9906)
			(stroke
				(width 0.1)
				(type default)
			)
			(layer "B.Fab")
		)
		(pad "1" smd rect
			(at 0 0 180)
			(size 0.508 0.508)
			(layers "B.Cu" "B.Mask" "B.Paste")
			(net "SGPIO_PCH_SATA_DOUT0")
		)
		(pad "2" smd rect
			(at 0 0.889 180)
			(size 0.508 0.508)
			(layers "B.Cu" "B.Mask" "B.Paste")
			(net "SGPIO_PCH_SATA_DOUT0_R")
		)
		(zone
			(layer "B.Cu")
			(hatch none 0.5)
			(connect_pads
				(clearance 0)
			)
			(min_thickness 0.25)
			(keepout
				(tracks allowed)
				(vias not_allowed)
				(pads allowed)
				(copperpour not_allowed)
				(footprints allowed)
			)
			(placement
				(enabled no)
				(sheetname "")
			)
			(fill
				(thermal_gap 0.5)
				(thermal_bridge_width 0.5)
				(island_removal_mode 0)
			)
			(polygon
				(pts
					(xy 391.922 -87.1855) (xy 391.414 -87.1855) (xy 391.414 -86.8045) (xy 391.922 -86.8045)
				)
			)
		)
		(zone
			(layer "B.Cu")
			(hatch none 0.5)
			(connect_pads
				(clearance 0)
			)
			(min_thickness 0.25)
			(keepout
				(tracks not_allowed)
				(vias allowed)
				(pads allowed)
				(copperpour not_allowed)
				(footprints allowed)
			)
			(placement
				(enabled no)
				(sheetname "")
			)
			(fill
				(thermal_gap 0.5)
				(thermal_bridge_width 0.5)
				(island_removal_mode 0)
			)
			(polygon
				(pts
					(xy 391.922 -86.8045) (xy 391.414 -86.8045) (xy 391.414 -87.1855) (xy 391.922 -87.1855)
				)
			)
		)
	)
	(footprint ""
		(layer "B.Cu")
		(at 104.775254 -68.17614 180)
		(property "Reference" "C8P33"
			(at 0 0 0)
			(layer "B.SilkS")
			(hide yes)
			(effects
				(font
					(size 1.27 1.27)
				)
				(justify mirror)
			)
		)
		(property "Value" ""
			(at 0 0 0)
			(layer "B.Fab")
			(effects
				(font
					(size 1.27 1.27)
				)
				(justify mirror)
			)
		)
		(duplicate_pad_numbers_are_jumpers no)
		(fp_poly
			(pts
				(xy 0.7239 -0.2159) (xy -0.7239 -0.2159) (xy -0.7239 1.9939) (xy 0.7239 1.9939)
			)
			(stroke
				(width 0)
				(type default)
			)
			(fill no)
			(layer "B.CrtYd")
		)
		(fp_line
			(start 0.7239 1.9939)
			(end -0.7239 1.9939)
			(stroke
				(width 0.1)
				(type default)
			)
			(layer "B.Fab")
		)
		(fp_line
			(start 0.7239 -0.2159)
			(end 0.7239 1.9939)
			(stroke
				(width 0.1)
				(type default)
			)
			(layer "B.Fab")
		)
		(fp_line
			(start -0.7239 1.9939)
			(end -0.7239 -0.2159)
			(stroke
				(width 0.1)
				(type default)
			)
			(layer "B.Fab")
		)
		(fp_line
			(start -0.7239 -0.2159)
			(end 0.7239 -0.2159)
			(stroke
				(width 0.1)
				(type default)
			)
			(layer "B.Fab")
		)
		(pad "1" smd rect
			(at 0 0)
			(size 1.27 1.016)
			(layers "B.Cu" "B.Mask" "B.Paste")
			(net "PVDDQ_GHJ")
		)
		(pad "2" smd rect
			(at 0 1.778)
			(size 1.27 1.016)
			(layers "B.Cu" "B.Mask" "B.Paste")
			(net "GND")
		)
		(zone
			(layer "B.Cu")
			(hatch none 0.5)
			(connect_pads
				(clearance 0)
			)
			(min_thickness 0.25)
			(keepout
				(tracks not_allowed)
				(vias allowed)
				(pads allowed)
				(copperpour not_allowed)
				(footprints allowed)
			)
			(placement
				(enabled no)
				(sheetname "")
			)
			(fill
				(thermal_gap 0.5)
				(thermal_bridge_width 0.5)
				(island_removal_mode 0)
			)
			(polygon
				(pts
					(xy 104.140254 -68.68414) (xy 105.410254 -68.68414) (xy 105.410254 -69.44614) (xy 104.140254 -69.44614)
				)
			)
		)
	)
	(footprint ""
		(layer "B.Cu")
		(at 382.07696 -105.005124 180)
		(property "Reference" "C3N23"
			(at 0 0 0)
			(layer "B.SilkS")
			(hide yes)
			(effects
				(font
					(size 1.27 1.27)
				)
				(justify mirror)
			)
		)
		(property "Value" ""
			(at 0 0 0)
			(layer "B.Fab")
			(effects
				(font
					(size 1.27 1.27)
				)
				(justify mirror)
			)
		)
		(duplicate_pad_numbers_are_jumpers no)
		(fp_rect
			(start 0.2794 0.9144)
			(end -0.2794 -0.1143)
			(stroke
				(width 0)
				(type default)
			)
			(fill no)
			(layer "B.CrtYd")
		)
		(fp_line
			(start 0.2794 0.9144)
			(end 0.2794 -0.1143)
			(stroke
				(width 0.1)
				(type default)
			)
			(layer "B.Fab")
		)
		(fp_line
			(start 0.2794 -0.1143)
			(end -0.2794 -0.1143)
			(stroke
				(width 0.1)
				(type default)
			)
			(layer "B.Fab")
		)
		(fp_line
			(start -0.2794 0.9144)
			(end 0.2794 0.9144)
			(stroke
				(width 0.1)
				(type default)
			)
			(layer "B.Fab")
		)
		(fp_line
			(start -0.2794 -0.1143)
			(end -0.2794 0.9144)
			(stroke
				(width 0.1)
				(type default)
			)
			(layer "B.Fab")
		)
		(pad "1" smd custom
			(at 0 0 90)
			(size 0.10414 0.10414)
			(layers "B.Cu" "B.Mask" "B.Paste")
			(net "P3V3_STBY")
			(options
				(clearance outline)
				(anchor circle)
			)
			(primitives
				(gr_poly
					(pts
						(xy -0.20828 -0.08636) (xy -0.20828 0.08636) (xy -0.08636 0.20828) (xy 0.086614 0.20828) (xy 0.20828 0.086614)
						(xy 0.20828 -0.08636) (xy 0.08636 -0.20828) (xy -0.08636 -0.20828)
					)
					(width 0)
					(fill yes)
				)
			)
		)
		(pad "2" smd custom
			(at 0 0.8001 90)
			(size 0.10414 0.10414)
			(layers "B.Cu" "B.Mask" "B.Paste")
			(net "GND")
			(options
				(clearance outline)
				(anchor circle)
			)
			(primitives
				(gr_poly
					(pts
						(xy -0.20828 -0.08636) (xy -0.20828 0.08636) (xy -0.08636 0.20828) (xy 0.086614 0.20828) (xy 0.20828 0.086614)
						(xy 0.20828 -0.08636) (xy 0.08636 -0.20828) (xy -0.08636 -0.20828)
					)
					(width 0)
					(fill yes)
				)
			)
		)
		(zone
			(layer "B.Cu")
			(hatch none 0.5)
			(connect_pads
				(clearance 0)
			)
			(min_thickness 0.25)
			(keepout
				(tracks not_allowed)
				(vias allowed)
				(pads allowed)
				(copperpour not_allowed)
				(footprints allowed)
			)
			(placement
				(enabled no)
				(sheetname "")
			)
			(fill
				(thermal_gap 0.5)
				(thermal_bridge_width 0.5)
				(island_removal_mode 0)
			)
			(polygon
				(pts
					(xy 381.98933 -105.214674) (xy 381.98933 -105.595674) (xy 382.16459 -105.595674) (xy 382.164844 -105.214674)
				)
			)
		)
		(zone
			(layer "B.Cu")
			(hatch none 0.5)
			(connect_pads
				(clearance 0)
			)
			(min_thickness 0.25)
			(keepout
				(tracks allowed)
				(vias not_allowed)
				(pads allowed)
				(copperpour not_allowed)
				(footprints allowed)
			)
			(placement
				(enabled no)
				(sheetname "")
			)
			(fill
				(thermal_gap 0.5)
				(thermal_bridge_width 0.5)
				(island_removal_mode 0)
			)
			(polygon
				(pts
					(xy 381.98933 -105.214674) (xy 381.98933 -105.595674) (xy 382.16459 -105.595674) (xy 382.164844 -105.214674)
				)
			)
		)
	)
)
